# T6G (Grand Teton) — schematic netlist excerpt (pin names and nets, part order shuffled) for the footprints in the layout excerpt that follows; sources: Cadence DE-HDL packaged netlist, KiCad conversion of 04192023_DAF0TMB3IC0_F0TG_MB_C_brd_V02_OCP.brd

J66  PICOPROBE_BXA  DELTA-L 4.0 EMPTY  pkg TRIANG_LAUNCH_3PXB  page 229
  \1_p\  = DELTA_L_85_5INCH_IN2_DP
  \2_n\  = DELTA_L_85_5INCH_IN2_DN
  \3_g\  = DELTA_L_GND_1

(kicad_pcb
	(version 20260206)
	(generator "pcbnew")
	(generator_version "10.0")
	(general
		(thickness 1.6)
		(legacy_teardrops no)
	)
	(paper "A4")
	(title_block
		(title "04192023_DAF0TMB3IC0_F0TG_MB_C_brd_V02_OCP.brd")
		(comment 1 "Grand Teton / footprints 2207-2207 of 8354")
	)
	(layers
		(0 "F.Cu" signal "TOP")
		(4 "In1.Cu" signal "GND")
		(6 "In2.Cu" signal "IN1")
		(8 "In3.Cu" signal "GND1")
		(10 "In4.Cu" signal "IN2")
		(12 "In5.Cu" signal "GND2")
		(14 "In6.Cu" signal "IN3")
		(16 "In7.Cu" signal "GND3")
		(18 "In8.Cu" signal "VCC")
		(20 "In9.Cu" signal "VCC1")
		(22 "In10.Cu" signal "GND4")
		(24 "In11.Cu" signal "IN4")
		(26 "In12.Cu" signal "GND5")
		(28 "In13.Cu" signal "IN5")
		(30 "In14.Cu" signal "GND6")
		(32 "In15.Cu" signal "IN6")
		(34 "In16.Cu" signal "GND7")
		(2 "B.Cu" signal "BOTTOM")
		(9 "F.Adhes" user "F.Adhesive")
		(11 "B.Adhes" user "B.Adhesive")
		(13 "F.Paste" user "Package Geometry/Pastemask Top")
		(15 "B.Paste" user "Package Geometry/Pastemask Bottom")
		(5 "F.SilkS" user "Ref Des/Silkscreen Top")
		(7 "B.SilkS" user "Ref Des/Silkscreen Bottom")
		(1 "F.Mask" user "Board Geometry/Soldermask Top")
		(3 "B.Mask" user "Board Geometry/Soldermask Bottom")
		(17 "Dwgs.User" user "User.Drawings")
		(19 "Cmts.User" user "User.Comments")
		(21 "Eco1.User" user "User.Eco1")
		(23 "Eco2.User" user "User.Eco2")
		(25 "Edge.Cuts" user "Board Geometry/Outline")
		(27 "Margin" user)
		(31 "F.CrtYd" user "Package Geometry/Place Bound Top")
		(29 "B.CrtYd" user "Package Geometry/Place Bound Bottom")
		(35 "F.Fab" user "Ref Des/Assembly Top")
		(33 "B.Fab" user "Ref Des/Assembly Bottom")
	)
	(footprint ""
		(layer "F.Cu")
		(at 440.78525 6.149848 180)
		(property "Reference" "J66"
			(at -4.541266 -1.222756 90)
			(unlocked yes)
			(layer "F.SilkS")
			(effects
				(font
					(size 0.7874 0.5842)
					(thickness 0.1524)
				)
				(justify left)
			)
		)
		(property "Value" ""
			(at 0 0 180)
			(layer "F.Fab")
			(effects
				(font
					(size 1.27 1.27)
				)
			)
		)
		(duplicate_pad_numbers_are_jumpers no)
		(fp_line
			(start 1.2192 2.06756)
			(end -1.2192 2.06756)
			(stroke
				(width 0.1524)
				(type default)
			)
			(layer "F.SilkS")
		)
		(fp_line
			(start 1.2192 -2.06756)
			(end 1.2192 2.06756)
			(stroke
				(width 0.1524)
				(type default)
			)
			(layer "F.SilkS")
		)
		(fp_line
			(start -1.2192 2.06756)
			(end -1.2192 -2.06756)
			(stroke
				(width 0.1524)
				(type default)
			)
			(layer "F.SilkS")
		)
		(fp_line
			(start -1.2192 -2.06756)
			(end 1.2192 -2.06756)
			(stroke
				(width 0.1524)
				(type default)
			)
			(layer "F.SilkS")
		)
		(pad "" np_thru_hole circle
			(at -2.8829 -1.27 90)
			(size 1.0414 1.0414)
			(drill 1.0414)
			(layers "*.Cu" "*.Mask")
			(clearance 0.381)
			(thermal_gap 0.381)
		)
		(pad "" np_thru_hole circle
			(at -2.8829 1.27 90)
			(size 1.0414 1.0414)
			(drill 1.0414)
			(layers "*.Cu" "*.Mask")
			(clearance 0.381)
			(thermal_gap 0.381)
		)
		(pad "" np_thru_hole circle
			(at 3.4671 -1.27 90)
			(size 1.0414 1.0414)
			(drill 1.0414)
			(layers "*.Cu" "*.Mask")
			(clearance 0.381)
			(thermal_gap 0.381)
		)
		(pad "" np_thru_hole circle
			(at 3.4671 1.27 90)
			(size 1.0414 1.0414)
			(drill 1.0414)
			(layers "*.Cu" "*.Mask")
			(clearance 0.381)
			(thermal_gap 0.381)
		)
		(pad "1" smd rect
			(at 0.8255 -0.249936 90)
			(size 0.3048 0.508)
			(layers "F.Cu" "F.Mask" "F.Paste")
			(net "DELTA_L_85_5INCH_IN2_DP")
		)
		(pad "2" smd rect
			(at 0.8255 0.249936 90)
			(size 0.3048 0.508)
			(layers "F.Cu" "F.Mask" "F.Paste")
			(net "DELTA_L_85_5INCH_IN2_DN")
		)
		(pad "3" smd circle
			(at 0 0 180)
			(size 0 0)
			(layers "F.Cu" "F.Mask" "F.Paste")
			(net "DELTA_L_GND_1")
		)
		(zone
			(layer "F.Cu")
			(hatch none 0.5)
			(connect_pads
				(clearance 0)
			)
			(min_thickness 0.25)
			(keepout
				(tracks not_allowed)
				(vias allowed)
				(pads allowed)
				(copperpour not_allowed)
				(footprints allowed)
			)
			(placement
				(enabled no)
				(sheetname "")
			)
			(fill
				(thermal_gap 0.5)
				(thermal_bridge_width 0.5)
				(island_removal_mode 0)
			)
			(polygon
				(pts
					(xy 439.66765 6.698488) (xy 439.66765 6.602984) (xy 440.26455 6.602984) (xy 440.26455 6.196584)
					(xy 439.66765 6.196584) (xy 439.66765 6.103112) (xy 440.26455 6.103112) (xy 440.26455 5.696712)
					(xy 439.66765 5.696712) (xy 439.66765 5.601208) (xy 440.36615 5.601208) (xy 440.36615 6.698488)
				)
			)
		)
		(zone
			(layers "F.Cu" "B.Cu" "In1.Cu" "In2.Cu" "In3.Cu" "In4.Cu" "In5.Cu" "In6.Cu"
				"In7.Cu" "In8.Cu" "In9.Cu" "In10.Cu" "In11.Cu" "In12.Cu" "In13.Cu" "In14.Cu"
				"In15.Cu" "In16.Cu"
			)
			(hatch none 0.5)
			(connect_pads
				(clearance 0)
			)
			(min_thickness 0.25)
			(keepout
				(tracks not_allowed)
				(vias allowed)
				(pads allowed)
				(copperpour not_allowed)
				(footprints allowed)
			)
			(placement
				(enabled no)
				(sheetname "")
			)
			(fill
				(thermal_gap 0.5)
				(thermal_bridge_width 0.5)
				(island_removal_mode 0)
			)
			(polygon
				(pts
					(arc
						(start 438.24525 4.879848)
						(mid 436.39105 4.879848)
						(end 438.24525 4.879848)
					)
				)
			)
		)
		(zone
			(layers "F.Cu" "B.Cu" "In1.Cu" "In2.Cu" "In3.Cu" "In4.Cu" "In5.Cu" "In6.Cu"
				"In7.Cu" "In8.Cu" "In9.Cu" "In10.Cu" "In11.Cu" "In12.Cu" "In13.Cu" "In14.Cu"
				"In15.Cu" "In16.Cu"
			)
			(hatch none 0.5)
			(connect_pads
				(clearance 0)
			)
			(min_thickness 0.25)
			(keepout
				(tracks not_allowed)
				(vias allowed)
				(pads allowed)
				(copperpour not_allowed)
				(footprints allowed)
			)
			(placement
				(enabled no)
				(sheetname "")
			)
			(fill
				(thermal_gap 0.5)
				(thermal_bridge_width 0.5)
				(island_removal_mode 0)
			)
			(polygon
				(pts
					(arc
						(start 438.24525 7.419848)
						(mid 436.39105 7.419848)
						(end 438.24525 7.419848)
					)
				)
			)
		)
		(zone
			(layers "F.Cu" "B.Cu" "In1.Cu" "In2.Cu" "In3.Cu" "In4.Cu" "In5.Cu" "In6.Cu"
				"In7.Cu" "In8.Cu" "In9.Cu" "In10.Cu" "In11.Cu" "In12.Cu" "In13.Cu" "In14.Cu"
				"In15.Cu" "In16.Cu"
			)
			(hatch none 0.5)
			(connect_pads
				(clearance 0)
			)
			(min_thickness 0.25)
			(keepout
				(tracks not_allowed)
				(vias allowed)
				(pads allowed)
				(copperpour not_allowed)
				(footprints allowed)
			)
			(placement
				(enabled no)
				(sheetname "")
			)
			(fill
				(thermal_gap 0.5)
				(thermal_bridge_width 0.5)
				(island_removal_mode 0)
			)
			(polygon
				(pts
					(arc
						(start 444.59525 4.879848)
						(mid 442.74105 4.879848)
						(end 444.59525 4.879848)
					)
				)
			)
		)
		(zone
			(layers "F.Cu" "B.Cu" "In1.Cu" "In2.Cu" "In3.Cu" "In4.Cu" "In5.Cu" "In6.Cu"
				"In7.Cu" "In8.Cu" "In9.Cu" "In10.Cu" "In11.Cu" "In12.Cu" "In13.Cu" "In14.Cu"
				"In15.Cu" "In16.Cu"
			)
			(hatch none 0.5)
			(connect_pads
				(clearance 0)
			)
			(min_thickness 0.25)
			(keepout
				(tracks not_allowed)
				(vias allowed)
				(pads allowed)
				(copperpour not_allowed)
				(footprints allowed)
			)
			(placement
				(enabled no)
				(sheetname "")
			)
			(fill
				(thermal_gap 0.5)
				(thermal_bridge_width 0.5)
				(island_removal_mode 0)
			)
			(polygon
				(pts
					(arc
						(start 444.59525 7.419848)
						(mid 442.74105 7.419848)
						(end 444.59525 7.419848)
					)
				)
			)
		)
	)
)
